# HDD Back Plane_Stackup.xlsx — Server_PCB_Test_Note (pcb-stackup)
| 編號(Number) | 內容(Item) | 附加檔案(Files) | 附加說明(Description) |
| 1 | Impedance Coupon test requirement |  | 1、板廠參考Excel範本在樣品階段(EVT, DVT, PVT)的出貨報告中提供所有阻抗測試條之量測結果，記錄其Min, Max, Mean, Sigma, USL, LSL, CP, CK, CPK等數值。 2、阻抗CPK的允收條件為 ≥ 1.0(PVT)；阻抗數值的允收條件為 ±10%(EVT, DVT, PVT)。 3、阻抗量測區間為TDR響應圖形中相對平坦的一個線段，取其中的 50%~70%區間來記錄其平均值、最小值、最大值。 4、阻抗測試條需擺放於折斷邊上。 |
| 4 | Delta-L coupon test requirement |  | 1、板廠參考Excel範本中的格式及步驟，在樣品階段(EVT, DVT, PVT)的出貨報告中提供10pcs Delta-L測試條之量測結果，出貨給緯創中山廠後，由緯創中山廠的人員在折下來的折斷邊之Delta-L測試條中，隨機挑選30 pcs寄回Wiwynn，Wiwynn再將此30 pcs coupon送至第三方單位(ITEQ或者ETC)測試。 2、Delta-L測試條的設計為85 ohm走線，需涵蓋的層面為85 ohm與100 ohm的所有走線層面。 3、損耗的允收條件為小於疊構中敘述的dB/inch數值且Failure Rate的條件為 < 0.3%(EVT, DVT, PVT)。 |
